(kicad_pcb
	(version 20260206)
	(generator "pcbnew")
	(generator_version "10.0")
	(general
		(thickness 1.6)
		(legacy_teardrops no)
	)
	(paper "A4")
	(title_block
		(title "9054_F0T_PDB_BD_GPU_F_V04_1213_1550_OCP.brd")
		(comment 1 "Grand Teton / footprints 25-26 of 608")
	)
	(layers
		(0 "F.Cu" signal "TOP")
		(4 "In1.Cu" signal "GND")
		(6 "In2.Cu" signal "IN1")
		(8 "In3.Cu" signal "GND1")
		(10 "In4.Cu" signal "VCC")
		(12 "In5.Cu" signal "VCC1")
		(14 "In6.Cu" signal "GND2")
		(16 "In7.Cu" signal "IN2")
		(18 "In8.Cu" signal "GND3")
		(2 "B.Cu" signal "BOTTOM")
		(9 "F.Adhes" user "F.Adhesive")
		(11 "B.Adhes" user "B.Adhesive")
		(13 "F.Paste" user "Package Geometry/Pastemask Top")
		(15 "B.Paste" user "Package Geometry/Pastemask Bottom")
		(5 "F.SilkS" user "Ref Des/Silkscreen Top")
		(7 "B.SilkS" user "Ref Des/Silkscreen Bottom")
		(1 "F.Mask" user "Board Geometry/Soldermask Top")
		(3 "B.Mask" user "Board Geometry/Soldermask Bottom")
		(17 "Dwgs.User" user "User.Drawings")
		(19 "Cmts.User" user "User.Comments")
		(21 "Eco1.User" user "User.Eco1")
		(23 "Eco2.User" user "User.Eco2")
		(25 "Edge.Cuts" user "Board Geometry/Outline")
		(27 "Margin" user)
		(31 "F.CrtYd" user "Package Geometry/Place Bound Top")
		(29 "B.CrtYd" user "Package Geometry/Place Bound Bottom")
		(35 "F.Fab" user "Ref Des/Assembly Top")
		(33 "B.Fab" user "Ref Des/Assembly Bottom")
	)
	(footprint ""
		(layer "F.Cu")
		(at 415.73958 -23.09876 180)
		(property "Reference" "R5918"
			(at 0 0 180)
			(layer "F.SilkS")
			(hide yes)
			(effects
				(font
					(size 1.27 1.27)
				)
			)
		)
		(property "Value" ""
			(at 0 0 180)
			(layer "F.Fab")
			(effects
				(font
					(size 1.27 1.27)
				)
			)
		)
		(duplicate_pad_numbers_are_jumpers no)
		(fp_line
			(start 0.7874 0.4064)
			(end -0.7874 0.4064)
			(stroke
				(width 0.1524)
				(type default)
			)
			(layer "F.SilkS")
		)
		(fp_line
			(start 0.7874 -0.4064)
			(end 0.7874 0.4064)
			(stroke
				(width 0.1524)
				(type default)
			)
			(layer "F.SilkS")
		)
		(fp_line
			(start -0.7874 0.4064)
			(end -0.7874 -0.4064)
			(stroke
				(width 0.1524)
				(type default)
			)
			(layer "F.SilkS")
		)
		(fp_line
			(start -0.7874 -0.4064)
			(end 0.7874 -0.4064)
			(stroke
				(width 0.1524)
				(type default)
			)
			(layer "F.SilkS")
		)
		(fp_line
			(start 0.67945 0.3048)
			(end 0.120396 0.3048)
			(stroke
				(width 0.1)
				(type default)
			)
			(layer "F.Fab")
		)
		(fp_line
			(start 0.67945 -0.3048)
			(end 0.67945 0.3048)
			(stroke
				(width 0.1)
				(type default)
			)
			(layer "F.Fab")
		)
		(fp_line
			(start 0.12065 -0.2794)
			(end 0.12065 -0.3048)
			(stroke
				(width 0.1)
				(type default)
			)
			(layer "F.Fab")
		)
		(fp_line
			(start 0.12065 -0.3048)
			(end 0.67945 -0.3048)
			(stroke
				(width 0.1)
				(type default)
			)
			(layer "F.Fab")
		)
		(fp_line
			(start 0.120396 0.3048)
			(end 0.120396 0.2794)
			(stroke
				(width 0.1)
				(type default)
			)
			(layer "F.Fab")
		)
		(fp_line
			(start 0.120396 0.2794)
			(end -0.12065 0.2794)
			(stroke
				(width 0.1)
				(type default)
			)
			(layer "F.Fab")
		)
		(fp_line
			(start -0.12065 0.3048)
			(end -0.67945 0.3048)
			(stroke
				(width 0.1)
				(type default)
			)
			(layer "F.Fab")
		)
		(fp_line
			(start -0.12065 0.2794)
			(end -0.12065 0.3048)
			(stroke
				(width 0.1)
				(type default)
			)
			(layer "F.Fab")
		)
		(fp_line
			(start -0.12065 -0.2794)
			(end 0.12065 -0.2794)
			(stroke
				(width 0.1)
				(type default)
			)
			(layer "F.Fab")
		)
		(fp_line
			(start -0.12065 -0.305054)
			(end -0.12065 -0.2794)
			(stroke
				(width 0.1)
				(type default)
			)
			(layer "F.Fab")
		)
		(fp_line
			(start -0.67945 0.3048)
			(end -0.67945 -0.305054)
			(stroke
				(width 0.1)
				(type default)
			)
			(layer "F.Fab")
		)
		(fp_line
			(start -0.67945 -0.305054)
			(end -0.12065 -0.305054)
			(stroke
				(width 0.1)
				(type default)
			)
			(layer "F.Fab")
		)
		(pad "1" smd rect
			(at -0.40005 0)
			(size 0.4572 0.508)
			(layers "F.Cu" "F.Mask" "F.Paste")
			(net "P12V_FAN_LED")
		)
		(pad "2" smd rect
			(at 0.40005 0)
			(size 0.4572 0.508)
			(layers "F.Cu" "F.Mask" "F.Paste")
			(net "P12V_LED_PD")
		)
	)
	(footprint ""
		(layer "F.Cu")
		(at 42.36339 -99.06)
		(property "Reference" "PC38"
			(at 6.17601 -5.05333 0)
			(unlocked yes)
			(layer "F.SilkS")
			(effects
				(font
					(size 0.7874 0.5842)
					(thickness 0.1524)
				)
				(justify left)
			)
		)
		(property "Value" ""
			(at 0 0 0)
			(layer "F.Fab")
			(effects
				(font
					(size 1.27 1.27)
				)
			)
		)
		(duplicate_pad_numbers_are_jumpers no)
		(fp_line
			(start -9.253728 3.750056)
			(end 9.249918 3.750056)
			(stroke
				(width 0.1524)
				(type default)
			)
			(layer "F.SilkS")
		)
		(fp_line
			(start 0 3.750056)
			(end -9.253728 3.750056)
			(stroke
				(width 0.1524)
				(type default)
			)
			(layer "F.SilkS")
		)
		(fp_circle
			(center 0 3.750056)
			(end 9.249918 3.750056)
			(stroke
				(width 0.1524)
				(type default)
			)
			(fill no)
			(layer "F.SilkS")
		)
		(fp_poly
			(pts
				(arc
					(start 9.249918 3.750056)
					(mid 0 12.999974)
					(end -9.249918 3.750056)
				)
			)
			(stroke
				(width 0)
				(type default)
			)
			(fill yes)
			(layer "F.SilkS")
		)
		(fp_circle
			(center 0 3.750056)
			(end 9.249918 3.750056)
			(stroke
				(width 0.1)
				(type default)
			)
			(fill no)
			(layer "F.Fab")
		)
		(pad "1" thru_hole rect
			(at 0 0)
			(size 1.778 1.778)
			(drill 1.27)
			(layers "*.Cu" "*.Mask")
			(remove_unused_layers no)
			(net "P52V_HS2")
			(clearance 0)
			(padstack
				(mode front_inner_back)
				(layer "Inner"
					(shape circle)
					(size 1.778 1.778)
					(clearance 0)
				)
				(layer "B.Cu"
					(shape rect)
					(size 1.778 1.778)
					(clearance 0)
				)
			)
		)
		(pad "2" thru_hole circle
			(at 0 7.500112)
			(size 1.778 1.778)
			(drill 1.27)
			(layers "*.Cu" "*.Mask")
			(remove_unused_layers no)
			(net "GND")
			(clearance 0)
		)
	)
)
